# TIMECARD (Time Appliance Project (Time Card)) — schematic netlist excerpt (pin names and nets, part order shuffled) for the footprints in the layout excerpt that follows; sources: Cadence DE-HDL packaged netlist, KiCad conversion of R4006-B0001-02_R01.brd

L19  FERRITEBEAD  600OHM 25%  pkg SMC_0603R_H037  page 20 : \1\ = VDD_BNO085 ; \2\ = XP3R3V_FPGA
DS20  OPTICAL  pkg SMC_DS_063X031_V4  page 26 : A = UNNAMED_14_OPTICAL_I194_A ; C = SG

(kicad_pcb
	(version 20260206)
	(generator "pcbnew")
	(generator_version "10.0")
	(general
		(thickness 1.6)
		(legacy_teardrops no)
	)
	(paper "A4")
	(title_block
		(title "timecard-production-celestica-r4006 — R4006-B0001-02_R01.brd")
		(comment 1 "Time Appliance Project (Time Card) / footprints 607-608 of 1113")
	)
	(layers
		(0 "F.Cu" signal "TOP")
		(4 "In1.Cu" signal "L02_GND1")
		(6 "In2.Cu" signal "L03_SIG1")
		(8 "In3.Cu" signal "L04_GND2")
		(10 "In4.Cu" signal "L05_VCC1")
		(12 "In5.Cu" signal "L06_VCC2")
		(14 "In6.Cu" signal "L07_GND3")
		(16 "In7.Cu" signal "L08_SIG2")
		(18 "In8.Cu" signal "L09_GND4")
		(2 "B.Cu" signal "BOTTOM")
		(9 "F.Adhes" user "F.Adhesive")
		(11 "B.Adhes" user "B.Adhesive")
		(13 "F.Paste" user "Package Geometry/Pastemask Top")
		(15 "B.Paste" user "Package Geometry/Pastemask Bottom")
		(5 "F.SilkS" user "Ref Des/Silkscreen Top")
		(7 "B.SilkS" user "Ref Des/Silkscreen Bottom")
		(1 "F.Mask" user "Board Geometry/Soldermask Top")
		(3 "B.Mask" user "Board Geometry/Soldermask Bottom")
		(17 "Dwgs.User" user "User.Drawings")
		(19 "Cmts.User" user "User.Comments")
		(21 "Eco1.User" user "User.Eco1")
		(23 "Eco2.User" user "User.Eco2")
		(25 "Edge.Cuts" user "Board Geometry/Outline")
		(27 "Margin" user)
		(31 "F.CrtYd" user "Package Geometry/Place Bound Top")
		(29 "B.CrtYd" user "Package Geometry/Place Bound Bottom")
		(35 "F.Fab" user "Ref Des/Assembly Top")
		(33 "B.Fab" user "Ref Des/Assembly Bottom")
	)
	(footprint ""
		(layer "F.Cu")
		(at 88.6714 -64.4144 90)
		(property "Reference" "L19"
			(at 12.8016 -10.01903 90)
			(unlocked yes)
			(layer "F.SilkS")
			(effects
				(font
					(size 0.7874 0.5842)
					(thickness 0.1524)
				)
			)
		)
		(property "Value" "VAL*"
			(at 0.014732 2.526538 90)
			(unlocked yes)
			(layer "F.Fab")
			(hide yes)
			(effects
				(font
					(size 0.7874 0.5842)
					(thickness 0.000001)
				)
			)
		)
		(property "Tolerance" "TOL*"
			(at 0.014732 3.503676 90)
			(unlocked yes)
			(layer "Cmts.User")
			(hide yes)
			(effects
				(font
					(size 0.7874 0.5842)
					(thickness 0.000001)
				)
			)
		)
		(property "User Part Number" "PARTNUM*"
			(at 0.02794 4.480814 90)
			(unlocked yes)
			(layer "Cmts.User")
			(hide yes)
			(effects
				(font
					(size 0.7874 0.5842)
					(thickness 0.000001)
				)
			)
		)
		(property "Device Type" "FERRITEBEAD-G191-10097-01,600OA"
			(at 0.014732 1.600708 90)
			(unlocked yes)
			(layer "F.Fab")
			(hide yes)
			(effects
				(font
					(size 0.7874 0.5842)
					(thickness 0.000001)
				)
			)
		)
		(duplicate_pad_numbers_are_jumpers no)
		(fp_line
			(start 1.3208 -0.7112)
			(end 1.3208 0.7112)
			(stroke
				(width 0.1)
				(type default)
			)
			(layer "F.SilkS")
		)
		(fp_line
			(start -1.3208 -0.7112)
			(end 1.3208 -0.7112)
			(stroke
				(width 0.1)
				(type default)
			)
			(layer "F.SilkS")
		)
		(fp_line
			(start 1.3208 0.7112)
			(end -1.3208 0.7112)
			(stroke
				(width 0.1)
				(type default)
			)
			(layer "F.SilkS")
		)
		(fp_line
			(start -1.3208 0.7112)
			(end -1.3208 -0.7112)
			(stroke
				(width 0.1)
				(type default)
			)
			(layer "F.SilkS")
		)
		(fp_rect
			(start -1.3208 0.7112)
			(end 1.3208 -0.7112)
			(stroke
				(width 0)
				(type default)
			)
			(fill no)
			(layer "F.CrtYd")
		)
		(fp_line
			(start 0.8128 -0.4572)
			(end 0.8128 0.4572)
			(stroke
				(width 0.1)
				(type default)
			)
			(layer "F.Fab")
		)
		(fp_line
			(start -0.8128 -0.4572)
			(end 0.8128 -0.4572)
			(stroke
				(width 0.1)
				(type default)
			)
			(layer "F.Fab")
		)
		(fp_line
			(start 0.8128 0.4572)
			(end -0.8128 0.4572)
			(stroke
				(width 0.1)
				(type default)
			)
			(layer "F.Fab")
		)
		(fp_line
			(start -0.8128 0.4572)
			(end -0.8128 -0.4572)
			(stroke
				(width 0.1)
				(type default)
			)
			(layer "F.Fab")
		)
		(pad "1" smd rect
			(at -0.6858 0 90)
			(size 0.762 0.8636)
			(layers "F.Cu" "F.Mask" "F.Paste")
			(net "VDD_BNO085")
		)
		(pad "2" smd rect
			(at 0.6858 0 90)
			(size 0.762 0.8636)
			(layers "F.Cu" "F.Mask" "F.Paste")
			(net "XP3R3V_FPGA")
		)
		(zone
			(layer "F.Cu")
			(hatch none 0.5)
			(connect_pads
				(clearance 0)
			)
			(min_thickness 0.25)
			(keepout
				(tracks allowed)
				(vias not_allowed)
				(pads allowed)
				(copperpour not_allowed)
				(footprints allowed)
			)
			(placement
				(enabled no)
				(sheetname "")
			)
			(fill
				(thermal_gap 0.5)
				(thermal_bridge_width 0.5)
				(island_removal_mode 0)
			)
			(polygon
				(pts
					(xy 89.1286 -64.262) (xy 89.1286 -64.5668) (xy 88.2142 -64.5668) (xy 88.2142 -64.262)
				)
			)
		)
		(zone
			(layer "F.Cu")
			(hatch none 0.5)
			(connect_pads
				(clearance 0)
			)
			(min_thickness 0.25)
			(keepout
				(tracks not_allowed)
				(vias allowed)
				(pads allowed)
				(copperpour not_allowed)
				(footprints allowed)
			)
			(placement
				(enabled no)
				(sheetname "")
			)
			(fill
				(thermal_gap 0.5)
				(thermal_bridge_width 0.5)
				(island_removal_mode 0)
			)
			(polygon
				(pts
					(xy 89.1286 -64.262) (xy 89.1286 -64.5668) (xy 88.2142 -64.5668) (xy 88.2142 -64.262)
				)
			)
		)
	)
	(footprint ""
		(layer "F.Cu")
		(at 153.049986 -104.350058 -90)
		(property "Reference" "DS20"
			(at 1.099058 -1.548384 90)
			(unlocked yes)
			(layer "F.SilkS")
			(effects
				(font
					(size 0.7874 0.5842)
					(thickness 0.1524)
				)
			)
		)
		(property "Value" ""
			(at 0 0 270)
			(layer "F.Fab")
			(effects
				(font
					(size 1.27 1.27)
				)
			)
		)
		(property "Device Type" "OPTICAL-G170-10143-01"
			(at 0.1778 1.483081 270)
			(unlocked yes)
			(layer "F.Fab")
			(hide yes)
			(effects
				(font
					(size 0.786892 0.583946)
					(thickness 0.000001)
				)
			)
		)
		(property "User Part Number" "PARTNUM*"
			(at 0.1778 2.422881 270)
			(unlocked yes)
			(layer "Cmts.User")
			(hide yes)
			(effects
				(font
					(size 0.786892 0.583946)
					(thickness 0.000001)
				)
			)
		)
		(duplicate_pad_numbers_are_jumpers no)
		(fp_line
			(start -1.1938 1.7272)
			(end -2.4638 1.7272)
			(stroke
				(width 0.1)
				(type default)
			)
			(layer "F.SilkS")
		)
		(fp_line
			(start -1.8288 1.0922)
			(end -1.8288 2.3622)
			(stroke
				(width 0.1)
				(type default)
			)
			(layer "F.SilkS")
		)
		(fp_line
			(start -1.397508 0.704088)
			(end -1.397508 -0.704088)
			(stroke
				(width 0.1)
				(type default)
			)
			(layer "F.SilkS")
		)
		(fp_line
			(start 1.397508 0.704088)
			(end -1.397508 0.704088)
			(stroke
				(width 0.1)
				(type default)
			)
			(layer "F.SilkS")
		)
		(fp_line
			(start -1.397508 -0.704088)
			(end 1.397508 -0.704088)
			(stroke
				(width 0.1)
				(type default)
			)
			(layer "F.SilkS")
		)
		(fp_line
			(start 1.397508 -0.704088)
			(end 1.397508 0.704088)
			(stroke
				(width 0.1)
				(type default)
			)
			(layer "F.SilkS")
		)
		(fp_poly
			(pts
				(xy 1.397508 0.704088) (xy 1.397508 -0.704088) (xy 1.905508 -0.704088) (xy 1.905508 0.704088)
			)
			(stroke
				(width 0)
				(type default)
			)
			(fill yes)
			(layer "F.SilkS")
		)
		(fp_poly
			(pts
				(xy -1.651508 0.958088) (xy 1.905508 0.958088) (xy 1.905508 -0.958088) (xy -1.651508 -0.958088)
			)
			(stroke
				(width 0)
				(type default)
			)
			(fill no)
			(layer "F.CrtYd")
		)
		(fp_line
			(start -1.4478 1.3462)
			(end -2.7178 1.3462)
			(stroke
				(width 0.1)
				(type default)
			)
			(layer "F.Fab")
		)
		(fp_line
			(start -2.0828 0.7112)
			(end -2.0828 1.9812)
			(stroke
				(width 0.1)
				(type default)
			)
			(layer "F.Fab")
		)
		(fp_line
			(start -0.850138 0.450088)
			(end 0.850138 0.450088)
			(stroke
				(width 0.1)
				(type default)
			)
			(layer "F.Fab")
		)
		(fp_line
			(start 0.850138 0.450088)
			(end 0.850138 -0.450088)
			(stroke
				(width 0.1)
				(type default)
			)
			(layer "F.Fab")
		)
		(fp_line
			(start -0.850138 -0.450088)
			(end -0.850138 0.450088)
			(stroke
				(width 0.1)
				(type default)
			)
			(layer "F.Fab")
		)
		(fp_line
			(start 0.850138 -0.450088)
			(end -0.850138 -0.450088)
			(stroke
				(width 0.1)
				(type default)
			)
			(layer "F.Fab")
		)
		(fp_poly
			(pts
				(xy 0.850138 -0.450088) (xy 0.850138 0.450088) (xy 0.342138 0.450088) (xy 0.342138 -0.450088)
			)
			(stroke
				(width 0)
				(type default)
			)
			(fill yes)
			(layer "F.Fab")
		)
		(fp_text user "C"
			(at 2.527808 0.268986 0)
			(unlocked yes)
			(layer "F.SilkS")
			(effects
				(font
					(size 0.635 0.4064)
					(thickness 0.1524)
				)
			)
		)
		(fp_text user "A"
			(at -1.028192 -1.255014 0)
			(unlocked yes)
			(layer "F.SilkS")
			(effects
				(font
					(size 0.635 0.4064)
					(thickness 0.1524)
				)
			)
		)
		(fp_text user "A"
			(at -1.020572 1.030986 0)
			(unlocked yes)
			(layer "F.Fab")
			(effects
				(font
					(size 0.7874 0.5842)
					(thickness 0.1524)
				)
			)
		)
		(fp_text user "C"
			(at 2.281428 -0.112014 0)
			(unlocked yes)
			(layer "F.Fab")
			(effects
				(font
					(size 0.7874 0.5842)
					(thickness 0.1524)
				)
			)
		)
		(pad "A" smd rect
			(at -0.749808 0 270)
			(size 0.7874 0.7874)
			(layers "F.Cu" "F.Mask" "F.Paste")
			(net "UNNAMED_14_OPTICAL_I194_A")
		)
		(pad "C" smd rect
			(at 0.749808 0 270)
			(size 0.7874 0.7874)
			(layers "F.Cu" "F.Mask" "F.Paste")
			(net "SG")
		)
	)
)
